FILE_TYPE = CONNECTIVITY;
{Allegro Design Entry HDL 16.6-p007 (v16-6-112F) 10/10/2012}
"PAGE_NUMBER" = 234;
0"NC";
1"GND\g";
2"GND\g";
3"P3V3_STBY\g";
4"GND\g";
5"P12V_STBY\g";
6"GND\g";
7"GND\g";
8"GND\g";
9"GND\g";
10"GND\g";
11"GND\g";
12"PVPP_KLM\g";
13"AGND_PVPP_KLM\g";
14"AGND_PVPP_KLM\g";
15"AGND_PVPP_KLM\g";
16"AGND_PVPP_KLM\g";
17"AGND_PVPP_KLM\g";
18"GND\g";
19"AGND_PVPP_KLM\g";
20"GND\g";
21"GND\g";
22"GND\g";
23"GND\g";
24"AGND_PVPP_KLM\g";
25"GND\g";
26"AGND_PVPP_KLM\g";
27"GND\g";
28"PVPP_KLM\g";
29"VR_PVPP_KLM_PHASE";
30"VR_PVPP_KLM_BOOT_R";
31"VSENSE_PVPP_KLM";
32"VR_COMP_PVPP_KLM";
33"VR_FB_PVPP_KLM";
34"VR_PVPP_KLM_SNUB";
35"VR_COMP_PVPP_KLM_3";
36"VR_COMP_RC_PVPP_KLM";
37"VR_PVPP_KLM_BOOT";
38"PWRGD_PVPP_KLM";
39"PWRGD_PVPP_KLM_R";
40"VR_FET_SW_P12V_STBY_PVPP_KLM";
41"VR_PVPP_KLM_ISET";
42"VR_PVPP_KLM_SS";
43"VR_VB_PVPP_KLM";
44"FM_PVPP_PVDDQ_CPU1_EN_KLM";
45"FM_PVPP_CPU1_EN";
46"GND\g";
%"CAP"
"1","(-6300,2400)","2","mstr_discrete","I129";
;
FIN"VR_1P2"
REUSE_ID"1"
CDS_SEC"1"
$SEC"1"
CDS_LOCATION"C4B5"
CDS_LIB"mstr_discrete"
BOM_COST"PVPP_KLM_VR"
ROOM"PVPP_KLM_VR"
MATERIAL"EMPTY"
LOCATION"C4B5"
PART_NUMBER"A36096-046"
VALUE"1000PF"
TOLERANCE"10%"
PACK_TYPE"0402LF"
VOLTAGE"50V";
"A"
$PN"1"45;
"B"
$PN"2"13;
%"CAP"
"1","(-7275,4150)","0","mstr_discrete","I130";
;
CDS_SEC"1"
$SEC"1"
CDS_LOCATION"C4B1"
CDS_LIB"mstr_discrete"
BOM_COST"PVPP_KLM_VR"
ROOM"PVPP_KLM_VR"
LOCATION"C4B1"
VALUE"47UF"
TOLERANCE"20%"
VOLTAGE"16V"
PART_NUMBER"D38464-007"
PACK_TYPE"1210"
MATERIAL"X6S";
"A"
$PN"1"40;
"B"
$PN"2"1;
%"GND"
"1","(-7275,3900)","0","mstr_symbols","I131";
;
HDL_POWER"GND"
SIZE"1B"
CDS_LIB"mstr_symbols"
VOLTAGE"0"
BODY_TYPE"PLUMBING"
ROOM"PVPP_KLM_VR"
BOM_COST"PVPP_KLM_VR";
"A\NAC"1;
%"GND"
"1","(-3875,475)","0","mstr_symbols","I138";
;
HDL_POWER"GND"
CDS_LIB"mstr_symbols"
VOLTAGE"0"
SIZE"1B"
BODY_TYPE"PLUMBING"
ROOM"PVPP_KLM_VR"
BOM_COST"PVPP_KLM_VR";
"A\NAC"2;
%"CAP"
"1","(-3875,725)","0","mstr_discrete","I139";
;
CDS_LOCATION"C4B8"
$SEC"1"
CDS_SEC"1"
REUSE_ID"17"
BOM_COST"PVPP_KLM_VR"
CDS_LIB"mstr_discrete"
ROOM"PVPP_KLM_VR"
PART_NUMBER"A36096-046"
PACK_TYPE"0402LF"
VOLTAGE"50V"
MATERIAL"X7R"
VALUE"1000PF"
LOCATION"C4B8"
TOLERANCE"10%";
"A"
$PN"1"39;
"B"
$PN"2"2;
%"RES"
"2","(-4750,1650)","2","mstr_discrete","I140";
;
CDS_SEC"1"
SEC"1"
SEC_TYPE"0402"
CDS_LOCATION"R4B6"
ROOM"PVPP_KLM_VR"
BOM_COST"PVPP_KLM_VR"
CDS_LIB"mstr_discrete"
LOCATION"R4B6"
VALUE"7.87K"
TOLERANCE"1.0%"
MATERIAL"CHIP"
WATTAGE"1/16W"
PART_NUMBER"G21796-242"
PACK_TYPE"0402";
"A"
$PN"1"41;
"B"
$PN"2"16;
%"P3V3_STBY"
"1","(-4225,1525)","0","mstr_symbols","I142";
;
VOLTAGE"+3.3V"
SIZE"1B"
CDS_LIB"mstr_symbols"
BODY_TYPE"PLUMBING"
HDL_POWER"P3V3_STBY";
"G\NAC"3;
%"RES"
"2","(-4225,1250)","0","mstr_discrete","I143";
;
CDS_SEC"1"
ROOM"PVPP_KLM_VR"
CDS_LOCATION"R4B10"
SEC"1"
SEC_TYPE"0402"
BOM_COST"PVPP_KLM_VR"
REUSE_ID"21"
CDS_LIB"mstr_discrete"
LOCATION"R4B10"
PART_NUMBER"G21796-026"
VALUE"1.00K"
PACK_TYPE"0402"
MATERIAL"CHIP"
WATTAGE"1/16W"
TOLERANCE"1%";
"A"
$PN"1"3;
"B"
$PN"2"39;
%"CAP"
"1","(-5600,2400)","0","mstr_discrete","I144";
;
CDS_SEC"1"
CDS_LOCATION"C6L12"
SEC"1"
REUSE_ID"26"
SEC_TYPE"0603"
BOM_COST"PVPP_KLM_VR"
ROOM"PVPP_KLM_VR"
CDS_LIB"mstr_discrete"
PART_NUMBER"E15431-003"
VALUE"4.7UF"
LOCATION"C6L12"
TOLERANCE"10%"
VOLTAGE"6.3V"
PACK_TYPE"0603"
MATERIAL"X6S";
"A"
$PN"1"43;
"B"
$PN"2"14;
%"CAP"
"1","(-5075,2175)","0","mstr_discrete","I146";
;
CDS_SEC"1"
SEC"1"
REUSE_ID"26"
BOM_COST"PVPP_KLM_VR"
SEC_TYPE"0402"
ROOM"PVPP_KLM_VR"
CDS_LOCATION"C4B6"
CDS_LIB"mstr_discrete"
VALUE"0.027UF"
VOLTAGE"16V"
PACK_TYPE"0402"
TOLERANCE"10%"
LOCATION"C4B6"
PART_NUMBER"A36096-129"
MATERIAL"X7R";
"A"
$PN"1"42;
"B"
$PN"2"15;
%"GND"
"1","(-4950,3825)","0","mstr_symbols","I151";
;
HDL_POWER"GND"
VOLTAGE"0"
CDS_LIB"mstr_symbols"
BODY_TYPE"PLUMBING"
SIZE"1B"
ROOM"PVPP_KLM_VR"
BOM_COST"PVPP_KLM_VR";
"A\NAC"4;
%"CAP"
"1","(-4950,4150)","0","mstr_discrete","I152";
;
FIN"VR_1P2"
$SEC"1"
CDS_SEC"1"
REUSE_ID"1"
CDS_LOCATION"C6L11"
ROOM"PVPP_KLM_VR"
BOM_COST"PVPP_KLM_VR"
CDS_LIB"mstr_discrete"
LOCATION"C6L11"
VALUE"1.0UF"
TOLERANCE"10%"
VOLTAGE"16V"
MATERIAL"X6S"
PACK_TYPE"0402"
PART_NUMBER"D97712-011";
"A"
$PN"1"40;
"B"
$PN"2"4;
%"P12V_STBY"
"1","(-7825,4500)","0","mstr_symbols","I153";
;
VOLTAGE"12.0V"
CDS_LIB"mstr_symbols"
SIZE"1B"
BODY_TYPE"PLUMBING"
HDL_POWER"P12V_STBY";
"G\NAC"5;
%"FERRITE"
"1","(-7500,4300)","0","mstr_discrete","I154";
;
CDS_SEC"1"
ROOM"PVPP_KLM_VR"
CDS_LOCATION"FB4A1"
SEC"1"
SEC_TYPE"SM"
TOLERANCE"1%"
CDS_LIB"mstr_discrete"
PACK_TYPE"SM"
PART_NUMBER"656554-051"
LOCATION"FB4A1"
MATERIAL"FB"
VALUE"22";
"A"
$PN"1"5;
"B"
$PN"2"40;
%"RES"
"1","(-4075,4200)","0","mstr_discrete","I155";
;
CDS_LOCATION"R4B13"
BOM_COST"PVPP_KLM_VR"
CDS_LIB"mstr_discrete"
ROOM"PVPP_KLM_VR"
$SEC"1"
CDS_SEC"1"
REUSE_ID"13"
PACK_TYPE"0402"
MATERIAL"CHIP"
LOCATION"R4B13"
PART_NUMBER"G21497-005"
TOLERANCE"5%"
VALUE"0.0"
WATTAGE"1/16W";
"B"
$PN"2"30;
"A"
$PN"1"37;
%"GND"
"1","(-3075,1925)","0","mstr_symbols","I157";
;
HDL_POWER"GND"
BOM_COST"PVPP_KLM_VR"
ROOM"PVPP_KLM_VR"
SIZE"1B"
BODY_TYPE"PLUMBING"
CDS_LIB"mstr_symbols"
VOLTAGE"0";
"A\NAC"6;
%"GND"
"1","(-2650,3150)","0","mstr_symbols","I161";
;
HDL_POWER"GND"
VOLTAGE"0"
CDS_LIB"mstr_symbols"
SIZE"1B"
BODY_TYPE"PLUMBING"
ROOM"PVPP_KLM_VR"
BOM_COST"PVPP_KLM_VR";
"A\NAC"7;
%"RES"
"2","(-2650,3350)","0","mstr_discrete","I162";
;
REUSE_ID"29"
CDS_SEC"1"
$SEC"1"
BOM_COST"PVPP_KLM_VR"
ROOM"PVPP_KLM_VR"
CDS_LOCATION"R4A7"
CDS_LIB"mstr_discrete"
PART_NUMBER"G21497-016"
MATERIAL"EMPTY"
VALUE"2.2"
TOLERANCE"5%"
PACK_TYPE"0402"
WATTAGE"1/16W"
LOCATION"R4A7";
"A"
$PN"1"34;
"B"
$PN"2"7;
%"CAP"
"1","(-2650,3700)","0","mstr_discrete","I163";
;
CDS_LOCATION"C4A16"
REUSE_ID"26"
BOM_COST"PVPP_KLM_VR"
CDS_SEC"1"
$SEC"1"
ROOM"PVPP_KLM_VR"
CDS_LIB"mstr_discrete"
MATERIAL"EMPTY"
LOCATION"C4A16"
VALUE"3300PF"
TOLERANCE"10%"
PACK_TYPE"0402LF"
VOLTAGE"50V"
PART_NUMBER"A36096-091";
"A"
$PN"1"29;
"B"
$PN"2"34;
%"INDUCTOR"
"1","(-2300,3850)","0","mstr_discrete","I164";
;
ROOM"PVPP_KLM_VR"
CDS_LIB"mstr_discrete"
BOM_COST"PVPP_KLM_VR"
REUSE_ID"30"
TOLERANCE"1%"
CDS_SEC"1"
$SEC"1"
CDS_LOCATION"L4A1"
PACK_TYPE"SM"
LOCATION"L4A1"
PART_NUMBER"E13358-018"
MATERIAL"IND"
VALUE"0.47UH";
"INA\NAC"
$PN"1"29;
"INB\NAC"
$PN"2"12;
%"GND"
"1","(-2075,3425)","0","mstr_symbols","I165";
;
SIZE"1B"
HDL_POWER"GND"
VOLTAGE"0"
CDS_LIB"mstr_symbols"
BODY_TYPE"PLUMBING"
ROOM"PVPP_KLM_VR"
BOM_COST"PVPP_KLM_VR";
"A\NAC"8;
%"GND"
"1","(-1750,3450)","0","mstr_symbols","I166";
;
HDL_POWER"GND"
SIZE"1B"
CDS_LIB"mstr_symbols"
VOLTAGE"0"
BODY_TYPE"PLUMBING"
ROOM"PVPP_KLM_VR"
BOM_COST"PVPP_KLM_VR";
"A\NAC"9;
%"CAPP"
"1","(-1750,3675)","0","mstr_discrete","I167";
;
REUSE_ID"28"
CDS_SEC"1"
$SEC"1"
CDS_LOCATION"C3B3"
CDS_LIB"mstr_discrete"
ROOM"PVPP_KLM_VR"
BOM_COST"PVPP_KLM_VR"
PART_NUMBER"724613-042"
PACK_TYPE"7343LF"
MATERIAL"POSCAP"
LOCATION"C3B3"
VALUE"330UF"
TOLERANCE"20%"
VOLTAGE"6.3V";
"B"
$PN"2"9;
"A"
$PN"1"12;
%"GND"
"1","(-1425,3450)","0","mstr_symbols","I175";
;
HDL_POWER"GND"
SIZE"1B"
VOLTAGE"0"
CDS_LIB"mstr_symbols"
BODY_TYPE"PLUMBING"
ROOM"PVPP_KLM_VR"
BOM_COST"PVPP_KLM_VR";
"A\NAC"10;
%"CAP"
"1","(-1150,3675)","0","mstr_discrete","I177";
;
$SEC"1"
CDS_SEC"1"
REUSE_ID"33"
ROOM"PVPP_KLM_VR"
CDS_LOCATION"C4B3"
BOM_COST"PVPP_KLM_VR"
CDS_LIB"mstr_discrete"
LOCATION"C4B3"
PART_NUMBER"C95333-006"
VALUE"47UF"
TOLERANCE"20%"
PACK_TYPE"0805"
MATERIAL"X6S"
VOLTAGE"4V";
"A"
$PN"1"12;
"B"
$PN"2"11;
%"GND"
"1","(-1150,3475)","0","mstr_symbols","I178";
;
HDL_POWER"GND"
VOLTAGE"0"
CDS_LIB"mstr_symbols"
SIZE"1B"
BODY_TYPE"PLUMBING"
BOM_COST"PVPP_KLM_VR"
ROOM"PVPP_KLM_VR";
"A\NAC"11;
%"GND"
"1","(-850,3500)","0","mstr_symbols","I179";
;
HDL_POWER"GND"
VOLTAGE"0"
CDS_LIB"mstr_symbols"
BODY_TYPE"PLUMBING"
SIZE"1B"
ROOM"PVPP_KLM_VR"
BOM_COST"PVPP_KLM_VR";
"A\NAC"46;
%"CAP"
"1","(-850,3650)","0","mstr_discrete","I180";
;
$SEC"1"
CDS_SEC"1"
REUSE_ID"33"
CDS_LIB"mstr_discrete"
BOM_COST"PVPP_KLM_VR"
CDS_LOCATION"C4B2"
ROOM"PVPP_KLM_VR"
PART_NUMBER"C95333-006"
LOCATION"C4B2"
VALUE"47UF"
TOLERANCE"20%"
VOLTAGE"4V"
PACK_TYPE"0805"
MATERIAL"X6S";
"A"
$PN"1"12;
"B"
$PN"2"46;
%"CAP"
"2","(-3375,4200)","2","mstr_discrete","I182";
;
CDS_LOCATION"C4B15"
$SEC"1"
CDS_SEC"1"
CDS_LIB"mstr_discrete"
ROOM"PVPP_KLM_VR"
REUSE_ID"27"
BOM_COST"PVPP_KLM_VR"
VALUE"0.1UF"
PART_NUMBER"602433-020"
LOCATION"C4B15"
VOLTAGE"25V"
TOLERANCE"10%"
PACK_TYPE"0603LF"
MATERIAL"X7R";
"A"
$PN"1"29;
"B"
$PN"2"30;
%"RES"
"2","(-2075,3675)","0","mstr_discrete","I183";
;
REUSE_ID"34"
BOM_COST"PVPP_KLM_VR"
CDS_SEC"1"
$SEC"1"
CDS_LOCATION"R4B2"
ROOM"PVPP_KLM_VR"
CDS_LIB"mstr_discrete"
LOCATION"R4B2"
VALUE"120.0"
TOLERANCE"1%"
MATERIAL"CHIP"
WATTAGE"1/10W"
PART_NUMBER"G22026-003"
PACK_TYPE"0603";
"A"
$PN"1"12;
"B"
$PN"2"8;
%"NCP3232L"
"1","(-3800,2875)","0","mstr_vreg","I184";
;
CDS_SEC"1"
CDS_LMAN_SYM_OUTLINE"-450,850,450,-900"
CDS_LIB"mstr_vreg"
PACK_TYPE"SM"
SEC_TYPE"SM"
SEC"1"
CDS_LOCATION"EU4A3"
PART_NUMBER"H86355-001"
LOCATION"EU4A3"
MATERIAL"IC";
"PG"
$PN"7"39;
"PGND<0>"
$PN"16"6;
"PGND<1>"
$PN"17"6;
"PGND<2>"
$PN"18"6;
"PGND<3>"
$PN"19"6;
"PGND<4>"
$PN"20"6;
"PGND<5>"
$PN"21"6;
"PGND<6>"
$PN"22"6;
"PGND<8>"
$PN"24"6;
"PGND<7>"
$PN"23"6;
"PGND<9>"
$PN"25"6;
"PGND<10>"
$PN"26"6;
"PGND<11>"
$PN"27"6;
"PGND<12>"
$PN"28"6;
"PGND<13>"
$PN"37"6;
"GND"
$PN"41"6;
"AGND"
$PN"5"17;
"EN"
$PN"40"44;
"SS"
$PN"1"42;
"ISET"
$PN"4"41;
"OTS"
$PN"6"19;
"VIN<6>"
$PN"14"40;
"VIN<7>"
$PN"42"40;
"VCC"
$PN"39"40;
"VIN<1>"
$PN"9"40;
"VIN<5>"
$PN"13"40;
"VIN<4>"
$PN"12"40;
"VIN<3>"
$PN"11"40;
"VIN<2>"
$PN"10"40;
"VIN<0>"
$PN"8"40;
"VB"
$PN"38"43;
"COMP"
$PN"3"35;
"FB"
$PN"2"33;
"VSWH<1>"
$PN"29"29;
"VSWH<0>"
$PN"15"29;
"VSW"
$PN"35"29;
"VSWH<2>"
$PN"30"29;
"VSWH<3>"
$PN"31"29;
"VSWH<4>"
$PN"32"29;
"VSWH<5>"
$PN"33"29;
"VSWH<6>"
$PN"34"29;
"BST"
$PN"36"37;
"VSWH<7>"
$PN"43"29;
%"PVPP_KLM"
"1","(-800,3975)","0","mstr_symbols","I185";
;
BOM_COST"PVPP_KLM_VR"
ROOM"PVPP_KLM_VR"
HDL_POWER"PVPP_KLM"
CDS_LIB"mstr_symbols"
BODY_TYPE"PLUMBING"
VOLTAGE"2.5V";
"G\NAC"12;
%"AGND_SCSI"
"1","(-6300,2075)","0","mstr_symbols","I187";
;
CDS_LIB"mstr_symbols"
BOM_COST"PVPP_KLM_VR"
ROOM"PVPP_KLM_VR"
VOLTAGE"0.0V"
BODY_TYPE"PLUMBING"
HDL_POWER"AGND_PVPP_KLM";
"A"13;
%"AGND_SCSI"
"1","(-5600,2100)","0","mstr_symbols","I188";
;
CDS_LIB"mstr_symbols"
VOLTAGE"0.0V"
BOM_COST"PVPP_KLM_VR"
BODY_TYPE"PLUMBING"
ROOM"PVPP_KLM_VR"
HDL_POWER"AGND_PVPP_KLM";
"A"14;
%"AGND_SCSI"
"1","(-5075,1950)","0","mstr_symbols","I189";
;
CDS_LIB"mstr_symbols"
VOLTAGE"0.0V"
BODY_TYPE"PLUMBING"
BOM_COST"PVPP_KLM_VR"
ROOM"PVPP_KLM_VR"
HDL_POWER"AGND_PVPP_KLM";
"A"15;
%"AGND_SCSI"
"1","(-4750,1350)","0","mstr_symbols","I190";
;
VOLTAGE"0"
CDS_LIB"mstr_symbols"
BODY_TYPE"PLUMBING"
HDL_POWER"AGND_PVPP_KLM";
"A"16;
%"AGND_SCSI"
"1","(-4375,1850)","0","mstr_symbols","I191";
;
BODY_TYPE"PLUMBING"
BOM_COST"PVPP_KLM_VR"
CDS_LIB"mstr_symbols"
VOLTAGE"0.0V"
ROOM"PVPP_KLM_VR"
HDL_POWER"AGND_PVPP_KLM";
"A"17;
%"GND"
"1","(-5175,3300)","0","mstr_symbols","I198";
;
SIZE"1B"
HDL_POWER"GND"
VOLTAGE"0"
CDS_LIB"mstr_symbols"
BODY_TYPE"PLUMBING"
BOM_COST"PVPP_KLM_VR"
ROOM"PVPP_KLM_VR";
"A\NAC"18;
%"CAP_A"
"1","(-5175,3525)","0","dev_discrete","I199";
;
CDS_LOCATION"C4A20"
CDS_SEC"1"
SEC_TYPE"0402V"
SEC"1"
CDS_LIB"dev_discrete"
LOCATION"C4A20"
PART_NUMBER"A36096-030"
VALUE"0.1UF"
TOLERANCE"10%"
PACK_TYPE"0402V"
VOLTAGE"16V"
MATERIAL"X7R";
"B"
$PN"2"18;
"A"
$PN"1"40;
%"AGND_SCSI"
"1","(-5400,2700)","0","mstr_symbols","I200";
;
VOLTAGE"0.0V"
BOM_COST"PVPP_KLM_VR"
CDS_LIB"mstr_symbols"
BODY_TYPE"PLUMBING"
ROOM"PVPP_KLM_VR"
HDL_POWER"AGND_PVPP_KLM";
"A"19;
%"RES"
"1","(-3350,975)","0","mstr_discrete","I201";
;
CDS_SEC"1"
SEC_TYPE"0402"
SEC"1"
CDS_LOCATION"R4B7"
ROOM"PVPP_KLM_VR"
CDS_LIB"mstr_discrete"
PACK_TYPE"0402"
LOCATION"R4B7"
PART_NUMBER"G21796-250"
TOLERANCE"1.0%"
MATERIAL"CHIP"
VALUE"22.1"
WATTAGE"1/16W";
"B"
$PN"2"38;
"A"
$PN"1"39;
%"CAP"
"1","(-6875,4100)","0","mstr_discrete","I202";
;
CDS_SEC"1"
SEC"1"
SEC_TYPE"0805"
CDS_LOCATION"C6L10"
CDS_LIB"mstr_discrete"
LOCATION"C6L10"
VALUE"10UF"
VOLTAGE"16V"
PART_NUMBER"C95333-007"
TOLERANCE"10%"
PACK_TYPE"0805"
MATERIAL"X6S";
"A"
$PN"1"40;
"B"
$PN"2"20;
%"CAP"
"1","(-6375,4100)","0","mstr_discrete","I203";
;
CDS_SEC"1"
SEC"1"
SEC_TYPE"0805"
CDS_LOCATION"C6M3"
CDS_LIB"mstr_discrete"
LOCATION"C6M3"
VALUE"10UF"
VOLTAGE"16V"
PART_NUMBER"C95333-007"
TOLERANCE"10%"
PACK_TYPE"0805"
MATERIAL"X6S";
"A"
$PN"1"40;
"B"
$PN"2"21;
%"CAP"
"1","(-5925,4100)","0","mstr_discrete","I204";
;
CDS_SEC"1"
SEC_TYPE"0805"
SEC"1"
CDS_LOCATION"C6M5"
CDS_LIB"mstr_discrete"
LOCATION"C6M5"
VALUE"10UF"
VOLTAGE"16V"
PART_NUMBER"C95333-007"
TOLERANCE"10%"
PACK_TYPE"0805"
MATERIAL"X6S";
"A"
$PN"1"40;
"B"
$PN"2"22;
%"CAP"
"1","(-5475,4100)","0","mstr_discrete","I205";
;
CDS_SEC"1"
SEC"1"
SEC_TYPE"0805"
CDS_LOCATION"C4A19"
CDS_LIB"mstr_discrete"
LOCATION"C4A19"
VALUE"10UF"
VOLTAGE"16V"
PART_NUMBER"C95333-007"
TOLERANCE"10%"
PACK_TYPE"0805"
MATERIAL"X6S";
"A"
$PN"1"40;
"B"
$PN"2"23;
%"GND"
"1","(-6875,3900)","0","mstr_symbols","I206";
;
HDL_POWER"GND"
SIZE"1B"
CDS_LIB"mstr_symbols"
VOLTAGE"0"
BODY_TYPE"PLUMBING"
ROOM"PVPP_KLM_VR"
BOM_COST"PVPP_KLM_VR";
"A\NAC"20;
%"GND"
"1","(-6375,3900)","0","mstr_symbols","I207";
;
HDL_POWER"GND"
SIZE"1B"
CDS_LIB"mstr_symbols"
VOLTAGE"0"
BODY_TYPE"PLUMBING"
ROOM"PVPP_KLM_VR"
BOM_COST"PVPP_KLM_VR";
"A\NAC"21;
%"GND"
"1","(-5925,3900)","0","mstr_symbols","I208";
;
SIZE"1B"
HDL_POWER"GND"
BODY_TYPE"PLUMBING"
CDS_LIB"mstr_symbols"
VOLTAGE"0"
ROOM"PVPP_KLM_VR"
BOM_COST"PVPP_KLM_VR";
"A\NAC"22;
%"GND"
"1","(-5475,3900)","0","mstr_symbols","I209";
;
HDL_POWER"GND"
SIZE"1B"
CDS_LIB"mstr_symbols"
VOLTAGE"0"
BODY_TYPE"PLUMBING"
ROOM"PVPP_KLM_VR"
BOM_COST"PVPP_KLM_VR";
"A\NAC"23;
%"CAPP"
"1","(-1425,3675)","0","mstr_discrete","I210";
;
CDS_SEC"1"
SEC_TYPE"7343"
SEC"1"
CDS_LOCATION"C6L8"
CDS_LIB"mstr_discrete"
LOCATION"C6L8"
VALUE"220UF"
TOLERANCE"20%"
VOLTAGE"4V"
MATERIAL"POSCAP"
PART_NUMBER"724613-067"
PACK_TYPE"7343";
"B"
$PN"2"10;
"A"
$PN"1"12;
%"CAP"
"2","(-2850,2450)","2","mstr_discrete","I211";
;
CDS_SEC"1"
ROOM"PVPP_KLM_VR"
SEC"1"
REUSE_ID"27"
BOM_COST"PVPP_KLM_VR"
SEC_TYPE"0402LF"
CDS_LOCATION"C4B9"
CDS_LIB"mstr_discrete"
PACK_TYPE"0402LF"
PART_NUMBER"A36096-075"
VALUE"2200PF"
TOLERANCE"10%"
LOCATION"C4B9"
MATERIAL"X7R"
VOLTAGE"50V";
"A"
$PN"1"36;
"B"
$PN"2"35;
%"CAP"
"2","(-2425,2825)","2","mstr_discrete","I212";
;
CDS_SEC"1"
SEC_TYPE"0402LF"
REUSE_ID"27"
SEC"1"
CDS_LIB"mstr_discrete"
BOM_COST"PVPP_KLM_VR"
CDS_LOCATION"C4B4"
ROOM"PVPP_KLM_VR"
TOLERANCE"5%"
MATERIAL"COG"
VALUE"100.0PF"
LOCATION"C4B4"
VOLTAGE"50V"
PACK_TYPE"0402LF"
PART_NUMBER"A36095-026";
"A"
$PN"1"33;
"B"
$PN"2"35;
%"RES"
"1","(-2150,2450)","0","mstr_discrete","I213";
;
CDS_SEC"1"
REUSE_ID"13"
SEC_TYPE"0402"
SEC"1"
ROOM"PVPP_KLM_VR"
CDS_LIB"mstr_discrete"
BOM_COST"PVPP_KLM_VR"
CDS_LOCATION"R4B8"
PART_NUMBER"G21796-242"
PACK_TYPE"0402"
MATERIAL"CHIP"
LOCATION"R4B8"
TOLERANCE"1.0%"
VALUE"7.87K"
WATTAGE"1/16W";
"B"
$PN"2"33;
"A"
$PN"1"36;
%"RES"
"1","(-1350,2925)","5","mstr_discrete","I214";
;
CDS_SEC"1"
SEC"1"
SEC_TYPE"0402"
SPOF"TRUE"
CDS_LOCATION"R4B3"
ROOM"PVPP_KLM_VR"
CDS_LIB"mstr_discrete"
LOCATION"R4B3"
PART_NUMBER"G21497-005"
VALUE"0.0"
TOLERANCE"5%"
PACK_TYPE"0402"
MATERIAL"CHIP"
WATTAGE"1/16W";
"B"
$PN"2"31;
"A"
$PN"1"12;
%"RES"
"2","(-1350,2175)","0","mstr_discrete","I215";
;
$SEC"1"
REUSE_ID"9"
CDS_SEC"1"
SPOF"TRUE"
BOM_COST"PVPP_KLM_VR"
ROOM"PVPP_KLM_VR"
CDS_LOCATION"R4B5"
CDS_LIB"mstr_discrete"
LOCATION"R4B5"
VALUE"20.0K"
TOLERANCE"1%"
PACK_TYPE"0402"
MATERIAL"CHIP"
WATTAGE"1/16W"
PART_NUMBER"G21796-040";
"A"
$PN"1"31;
"B"
$PN"2"33;
%"RES"
"2","(-1350,1550)","0","mstr_discrete","I216";
;
SPOF"TRUE"
REUSE_ID"7"
CDS_SEC"1"
$SEC"1"
CDS_LOCATION"R4B4"
CDS_LIB"mstr_discrete"
BOM_COST"PVPP_KLM_VR"
ROOM"PVPP_KLM_VR"
PART_NUMBER"G21796-146"
LOCATION"R4B4"
VALUE"6.34K"
TOLERANCE"1%"
WATTAGE"1/16W"
PACK_TYPE"0402"
MATERIAL"CHIP";
"A"
$PN"1"33;
"B"
$PN"2"24;
%"CAP"
"1","(-1025,2075)","0","mstr_discrete","I218";
;
CDS_SEC"1"
SPOF"TRUE"
BOM_COST"PVPP_KLM_VR"
REUSE_ID"26"
SEC_TYPE"0402LF"
SEC"1"
CDS_LOCATION"C4B7"
ROOM"PVPP_KLM_VR"
CDS_LIB"mstr_discrete"
LOCATION"C4B7"
VALUE"2200PF"
VOLTAGE"50V"
TOLERANCE"10%"
PART_NUMBER"A36096-075"
PACK_TYPE"0402LF"
MATERIAL"X7R";
"A"
$PN"1"32;
"B"
$PN"2"33;
%"RES"
"2","(-1025,2625)","0","mstr_discrete","I219";
;
CDS_SEC"1"
SPOF"TRUE"
BOM_COST"PVPP_KLM_VR"
REUSE_ID"9"
SEC_TYPE"0402"
SEC"1"
CDS_LOCATION"R4B9"
ROOM"PVPP_KLM_VR"
CDS_LIB"mstr_discrete"
LOCATION"R4B9"
VALUE"1.0K"
TOLERANCE"0.1%"
WATTAGE"1/16W"
PACK_TYPE"0402"
MATERIAL"CHIP"
PART_NUMBER"G85996-004";
"A"
$PN"1"31;
"B"
$PN"2"32;
%"RES"
"1","(-5925,2825)","0","mstr_discrete","I220";
;
ROOM"PVCCIN_CPU0_VR"
CDS_LOCATION"R4B1"
$SEC"1"
CDS_SEC"1"
CDS_LIB"mstr_discrete"
PACK_TYPE"0402"
LOCATION"R4B1"
PART_NUMBER"G21497-005"
MATERIAL"CHIP"
VALUE"0.0"
TOLERANCE"5%"
WATTAGE"1/16W";
"B"
$PN"2"44;
"A"
$PN"1"45;
%"AGND_SCSI"
"1","(-1350,1175)","0","mstr_symbols","I221";
;
BOM_COST"PVPP_KLM_VR"
CDS_LIB"mstr_symbols"
BODY_TYPE"PLUMBING"
ROOM"PVPP_KLM_VR"
VOLTAGE"0.0V"
HDL_POWER"AGND_PVPP_KLM";
"A"24;
%"GND"
"1","(-1450,550)","0","mstr_symbols","I27";
;
VOLTAGE"0"
CDS_LIB"mstr_symbols"
HDL_POWER"GND"
SIZE"1B"
BODY_TYPE"PLUMBING"
ROOM"PVPP_KLM_VR"
BOM_COST"PVPP_KLM_VR";
"A\NAC"25;
%"AGND_SCSI"
"1","(-900,550)","0","mstr_symbols","I28";
;
CDS_LIB"mstr_symbols"
BODY_TYPE"PLUMBING"
VOLTAGE"0.0V"
BOM_COST"PVPP_KLM_VR"
ROOM"PVPP_KLM_VR"
HDL_POWER"AGND_PVPP_KLM";
"A"26;
%"RES"
"1","(-1150,650)","0","mstr_discrete","I29";
;
CDS_LOCATION"R4B14"
$SEC"1"
CDS_SEC"1"
CDS_LIB"mstr_discrete"
ROOM"PVPP_KLM_VR"
PART_NUMBER"G21497-005"
TOLERANCE"5%"
LOCATION"R4B14"
VALUE"0.0"
MATERIAL"CHIP"
WATTAGE"1/16W"
PACK_TYPE"0402";
"B"
$PN"2"26;
"A"
$PN"1"25;
%"GND"
"1","(-825,3475)","0","mstr_symbols","I66";
;
HDL_POWER"GND"
SIZE"1B"
CDS_LIB"mstr_symbols"
VOLTAGE"0"
BODY_TYPE"PLUMBING"
ROOM"PVPP_KLM_VR"
BOM_COST"PVPP_KLM_VR";
"A\NAC"0;
%"CAP"
"1","(-5150,725)","0","mstr_discrete","I84";
;
CDS_SEC"1"
VOLTAGE"4V"
BOM_COST"MEM_VRD_PVPP_AB"
SEC_TYPE"0603LF"
SEC"1"
CDS_LOCATION"C3B2"
ROOM"PVPP_KLM_VR"
CDS_LIB"mstr_discrete"
LOCATION"C3B2"
PART_NUMBER"E15431-001"
VALUE"10UF"
TOLERANCE"20%"
PACK_TYPE"0603LF"
MATERIAL"X6S";
"A"
$PN"1"28;
"B"
$PN"2"27;
%"GND"
"1","(-5225,400)","0","mstr_symbols","I85";
;
HDL_POWER"GND"
BOM_COST"MEM_VRD_PVPP_AB"
VOLTAGE"0"
CDS_LIB"mstr_symbols"
SIZE"1B"
BODY_TYPE"PLUMBING"
ROOM"PVPP_KLM_VR";
"A\NAC"27;
%"CAP"
"1","(-5400,700)","0","mstr_discrete","I86";
;
ROOM"PVPP_KLM_VR"
CDS_LOCATION"C3A8"
$SEC"1"
CDS_SEC"1"
BOM_COST"MEM_VRD_PVPP_AB"
VOLTAGE"4V"
CDS_LIB"mstr_discrete"
PART_NUMBER"E15431-001"
LOCATION"C3A8"
VALUE"10UF"
MATERIAL"X6S"
TOLERANCE"20%"
PACK_TYPE"0603LF";
"A"
$PN"1"28;
"B"
$PN"2"27;
%"CAP"
"1","(-5675,700)","0","mstr_discrete","I87";
;
CDS_SEC"1"
BOM_COST"MEM_VRD_PVPP_AB"
$SEC"1"
CDS_LOCATION"C7L3"
ROOM"PVPP_KLM_VR"
VOLTAGE"4V"
CDS_LIB"mstr_discrete"
PART_NUMBER"E15431-001"
LOCATION"C7L3"
VALUE"10UF"
TOLERANCE"20%"
MATERIAL"X6S"
PACK_TYPE"0603LF";
"A"
$PN"1"28;
"B"
$PN"2"27;
%"CAP"
"1","(-5950,725)","0","mstr_discrete","I88";
;
CDS_SEC"1"
$SEC"1"
BOM_COST"MEM_VRD_PVPP_AB"
ROOM"PVPP_KLM_VR"
CDS_LOCATION"C7L2"
CDS_LIB"mstr_discrete"
VOLTAGE"4V"
PART_NUMBER"E15431-001"
LOCATION"C7L2"
VALUE"10UF"
TOLERANCE"20%"
PACK_TYPE"0603LF"
MATERIAL"X6S";
"A"
$PN"1"28;
"B"
$PN"2"27;
%"CAP"
"1","(-6250,725)","0","mstr_discrete","I89";
;
CDS_SEC"1"
$SEC"1"
BOM_COST"MEM_VRD_PVPP_AB"
ROOM"PVPP_KLM_VR"
CDS_LOCATION"C7L7"
CDS_LIB"mstr_discrete"
VOLTAGE"4V"
LOCATION"C7L7"
PART_NUMBER"E15431-001"
VALUE"10UF"
TOLERANCE"20%"
PACK_TYPE"0603LF"
MATERIAL"X6S";
"A"
$PN"1"28;
"B"
$PN"2"27;
%"CAP"
"1","(-6550,725)","0","mstr_discrete","I90";
;
BOM_COST"MEM_VRD_PVPP_AB"
CDS_SEC"1"
$SEC"1"
CDS_LOCATION"C7L6"
ROOM"PVPP_KLM_VR"
CDS_LIB"mstr_discrete"
VOLTAGE"4V"
LOCATION"C7L6"
PART_NUMBER"E15431-001"
VALUE"10UF"
PACK_TYPE"0603LF"
TOLERANCE"20%"
MATERIAL"X6S";
"A"
$PN"1"28;
"B"
$PN"2"27;
%"CAP"
"1","(-6825,725)","0","mstr_discrete","I91";
;
BOM_COST"MEM_VRD_PVPP_AB"
CDS_SEC"1"
$SEC"1"
CDS_LOCATION"C7M4"
ROOM"PVPP_KLM_VR"
CDS_LIB"mstr_discrete"
VOLTAGE"4V"
PART_NUMBER"E15431-001"
PACK_TYPE"0603LF"
VALUE"10UF"
LOCATION"C7M4"
TOLERANCE"20%"
MATERIAL"X6S";
"A"
$PN"1"28;
"B"
$PN"2"27;
%"CAP"
"1","(-7125,725)","0","mstr_discrete","I92";
;
$SEC"1"
CDS_SEC"1"
ROOM"PVPP_KLM_VR"
BOM_COST"MEM_VRD_PVPP_AB"
CDS_LOCATION"C7M3"
CDS_LIB"mstr_discrete"
VOLTAGE"4V"
PART_NUMBER"E15431-001"
PACK_TYPE"0603LF"
VALUE"10UF"
LOCATION"C7M3"
TOLERANCE"20%"
MATERIAL"X6S";
"A"
$PN"1"28;
"B"
$PN"2"27;
%"CAP"
"1","(-7400,700)","0","mstr_discrete","I93";
;
CDS_SEC"1"
$SEC"1"
ROOM"PVPP_KLM_VR"
BOM_COST"MEM_VRD_PVPP_AB"
CDS_LOCATION"C3A4"
CDS_LIB"mstr_discrete"
VOLTAGE"4V"
PART_NUMBER"E15431-001"
LOCATION"C3A4"
VALUE"10UF"
TOLERANCE"20%"
MATERIAL"X6S"
PACK_TYPE"0603LF";
"A"
$PN"1"28;
"B"
$PN"2"27;
%"CAP"
"1","(-7650,725)","0","mstr_discrete","I94";
;
CDS_SEC"1"
$SEC"1"
ROOM"PVPP_KLM_VR"
BOM_COST"MEM_VRD_PVPP_AB"
CDS_LOCATION"C3B1"
CDS_LIB"mstr_discrete"
VOLTAGE"4V"
PART_NUMBER"E15431-001"
LOCATION"C3B1"
VALUE"10UF"
PACK_TYPE"0603LF"
TOLERANCE"20%"
MATERIAL"X6S";
"A"
$PN"1"28;
"B"
$PN"2"27;
%"CAP"
"1","(-7925,725)","0","mstr_discrete","I95";
;
BOM_COST"MEM_VRD_PVPP_AB"
CDS_SEC"1"
$SEC"1"
CDS_LOCATION"C3A7"
ROOM"PVPP_KLM_VR"
CDS_LIB"mstr_discrete"
VOLTAGE"4V"
PART_NUMBER"E15431-001"
LOCATION"C3A7"
VALUE"10UF"
TOLERANCE"20%"
PACK_TYPE"0603LF"
MATERIAL"X6S";
"A"
$PN"1"28;
"B"
$PN"2"27;
%"PVPP_KLM"
"1","(-8175,1000)","0","mstr_symbols","I96";
;
BOM_COST"MEM_VRD_PVPP_AB"
ROOM"PVPP_KLM_VR"
HDL_POWER"PVPP_KLM"
CDS_LIB"mstr_symbols"
VOLTAGE"2.5V"
BODY_TYPE"PLUMBING";
"G\NAC"28;
%"CAP"
"1","(-8175,725)","0","mstr_discrete","I97";
;
$SEC"1"
CDS_SEC"1"
ROOM"PVPP_KLM_VR"
BOM_COST"MEM_VRD_PVPP_AB"
CDS_LOCATION"C3A3"
VOLTAGE"4V"
CDS_LIB"mstr_discrete"
PART_NUMBER"E15431-001"
VALUE"10UF"
LOCATION"C3A3"
TOLERANCE"20%"
PACK_TYPE"0603LF"
MATERIAL"X6S";
"A"
$PN"1"28;
"B"
$PN"2"27;
END.
